FILE_TYPE = CONNECTIVITY;
{Allegro Design Entry HDL 17.2-2016 S081 (4005846) 1/11/2022}
"PAGE_NUMBER" = 32;
0"NC";
1"P3V3_AUX\g";
2"P3V3_AUX\g";
3"P3V3_RGM\g";
4"GND\g";
5"GND\g";
6"GND\g";
7"GND\g";
8"GND\g";
9"J7_P1";
10"JTAG_SCM_CONN_TDO";
11"JTAG_SCM_CONN_TDI";
12"JTAG_SCM_PLD_R1_JTAGEN";
13"TP_PLD_CONN_P5";
14"JTAG_SCM_CONN_TMS";
15"JTAG_SCM_CONN_TCK";
16"JTAG_SCM_CONN_TDO";
17"JTAG_MB_TDI";
18"JTAG_MB_TMS";
19"JTAG_MB_TDO";
20"JTAG_MB_TDI";
21"JTAG_MB_TMS";
22"JTAG_MB_TDO";
23"JTAG_MB_TRST_N";
24"JTAG_MB_TCK";
25"JTAG_SCM_NTRST";
26"JTAG_MB_TCK";
27"JTAG_MB_TRST_N";
28"JTAG_SCM_PLD_JTAGEN";
29"JTAG_SCM_PLD_TCK";
30"JTAG_SCM_TCK";
31"JTAG_SCM_TMS";
32"JTAG_SCM_TDI";
33"JTAG_SCM_TCK";
34"JTAG_1_BMC_TDO_R";
35"JTAG_1_BMC_TDI_R";
36"JTAG_1_BMC_TMS_R";
37"JTAG_1_BMC_TCK_R";
38"JTAG_1_BMC_TRST_R";
39"JTAG_SCM_PLD_TDI";
40"JTAG_SCM_PLD_TMS";
41"JTAG_SCM_PLD_TDO";
42"JTAG_SCM_CONN_TDI";
43"JTAG_SCM_TDO";
44"JTAG_SCM_TDI";
45"JTAG_SCM_TMS";
46"JTAG_SCM_TDO";
47"JTAG_SCM_CONN_TMS";
48"JTAG_SCM_CONN_TCK";
%"Q_RES"
"1","(-200,450)","0","pure_quanta","I103";
;
MATERIAL"CHIP"
VALUE"10K"
CDS_LIB"pure_quanta"
TOLERANCE"1%"
WATTAGE"1/16W"
PACK_TYPE"0402LF"
PART_NUMBER"CS31002FB08"
LOCATION"R226"
$SEC"1"
CDS_SEC"1";
"B"
$PN"2"20;
"A"
$PN"1"1;
%"Q_RES"
"1","(-200,250)","0","pure_quanta","I104";
;
VALUE"10K"
MATERIAL"CHIP"
CDS_LIB"pure_quanta"
TOLERANCE"1%"
WATTAGE"1/16W"
PACK_TYPE"0402LF"
PART_NUMBER"CS31002FB08"
LOCATION"R227"
$SEC"1"
CDS_SEC"1";
"B"
$PN"2"21;
"A"
$PN"1"1;
%"Q_RES"
"1","(-200,125)","0","pure_quanta","I105";
;
MATERIAL"CHIP"
VALUE"10K"
CDS_LIB"pure_quanta"
TOLERANCE"1%"
WATTAGE"1/16W"
PACK_TYPE"0402LF"
PART_NUMBER"CS31002FB08"
LOCATION"R230"
$SEC"1"
CDS_SEC"1";
"B"
$PN"2"22;
"A"
$PN"1"1;
%"Q_RES"
"1","(-200,-225)","0","pure_quanta","I106";
;
MATERIAL"EMPTY"
VALUE"4.7K"
CDS_LIB"pure_quanta"
PART_NUMBER"CS24702FB06"
PACK_TYPE"0402LF"
WATTAGE"1/16W"
TOLERANCE"1%"
LOCATION"R229"
$SEC"1"
CDS_SEC"1";
"B"
$PN"2"23;
"A"
$PN"1"7;
%"Q_RES"
"1","(-200,-350)","0","pure_quanta","I107";
;
VALUE"10K"
MATERIAL"EMPTY"
CDS_LIB"pure_quanta"
WATTAGE"1/16W"
TOLERANCE"1%"
PACK_TYPE"0402LF"
PART_NUMBER"CS31002FB08"
LOCATION"R228"
$SEC"1"
CDS_SEC"1";
"B"
$PN"2"24;
"A"
$PN"1"7;
%"UNIVERSAL_POWER"
"1","(-650,725)","0","logical_power","I108";
;
HDL_POWER"P3V3_AUX"
CDS_LIB"logical_power";
"A"1;
%"UNIVERSAL_GND"
"1","(-650,-675)","0","logical_power","I113";
;
CDS_LIB"logical_power"
HDL_POWER"GND";
"A"7;
%"Q_RES"
"1","(-2425,425)","0","pure_quanta","I117";
;
VALUE"10K"
MATERIAL"CHIP"
CDS_LIB"pure_quanta"
TOLERANCE"1%"
WATTAGE"1/16W"
PACK_TYPE"0402LF"
PART_NUMBER"CS31002FB08"
LOCATION"R203"
$SEC"1"
CDS_SEC"1";
"B"
$PN"2"45;
"A"
$PN"1"3;
%"UNIVERSAL_POWER"
"1","(-2800,575)","0","logical_power","I118";
;
HDL_POWER"P3V3_RGM"
CDS_LIB"logical_power";
"A"3;
%"Q_RES"
"1","(-2425,275)","0","pure_quanta","I119";
;
MATERIAL"CHIP"
VALUE"10K"
CDS_LIB"pure_quanta"
PART_NUMBER"CS31002FB08"
PACK_TYPE"0402LF"
WATTAGE"1/16W"
TOLERANCE"1%"
LOCATION"R523"
$SEC"1"
CDS_SEC"1";
"B"
$PN"2"46;
"A"
$PN"1"3;
%"Q_RES"
"1","(-2425,350)","0","pure_quanta","I120";
;
MATERIAL"CHIP"
VALUE"10K"
CDS_LIB"pure_quanta"
TOLERANCE"1%"
WATTAGE"1/16W"
PACK_TYPE"0402LF"
PART_NUMBER"CS31002FB08"
LOCATION"R204"
$SEC"1"
CDS_SEC"1";
"B"
$PN"2"44;
"A"
$PN"1"3;
%"UNIVERSAL_GND"
"1","(-2800,-650)","0","logical_power","I123";
;
CDS_LIB"logical_power"
HDL_POWER"GND";
"A"8;
%"Q_RES"
"1","(-1525,3775)","0","pure_quanta","I126";
;
VALUE"33.2"
MATERIAL"CHIP"
TOLERANCE"1%"
PART_NUMBER"CS03322FB03"
PACK_TYPE"0402LF"
WATTAGE"1/16W"
CDS_LIB"pure_quanta"
LOCATION"R510"
$SEC"1"
CDS_SEC"1";
"B"
$PN"2"29;
"A"
$PN"1"30;
%"Q_RES"
"1","(-1525,3725)","0","pure_quanta","I127";
;
VALUE"33.2"
MATERIAL"CHIP"
TOLERANCE"1%"
PART_NUMBER"CS03322FB03"
PACK_TYPE"0402LF"
WATTAGE"1/16W"
CDS_LIB"pure_quanta"
LOCATION"R511"
$SEC"1"
CDS_SEC"1";
"B"
$PN"2"40;
"A"
$PN"1"31;
%"Q_RES"
"1","(-1525,3625)","0","pure_quanta","I128";
;
VALUE"33.2"
MATERIAL"CHIP"
TOLERANCE"1%"
PART_NUMBER"CS03322FB03"
PACK_TYPE"0402LF"
WATTAGE"1/16W"
CDS_LIB"pure_quanta"
LOCATION"R513"
$SEC"1"
CDS_SEC"1";
"B"
$PN"2"41;
"A"
$PN"1"43;
%"Q_RES"
"1","(-1525,3675)","0","pure_quanta","I129";
;
MATERIAL"CHIP"
VALUE"33.2"
TOLERANCE"1%"
PART_NUMBER"CS03322FB03"
PACK_TYPE"0402LF"
WATTAGE"1/16W"
CDS_LIB"pure_quanta"
LOCATION"R512"
$SEC"1"
CDS_SEC"1";
"B"
$PN"2"39;
"A"
$PN"1"32;
%"Q_RES"
"1","(-2425,50)","0","pure_quanta","I131";
;
VALUE"10K"
MATERIAL"EMPTY"
CDS_LIB"pure_quanta"
PART_NUMBER"CS31002FB08"
PACK_TYPE"0402LF"
TOLERANCE"1%"
WATTAGE"1/16W"
LOCATION"R834"
$SEC"1"
CDS_SEC"1";
"B"
$PN"2"33;
"A"
$PN"1"3;
%"CONN8_210HP1080BR1"
"1","(2675,3350)","2","pure_quanta","I132";
;
PART_NUMBER"DFHD08MS392"
VALUE"CONN8_210-HP1-080BR1"
PART_TYPE"THLF"
MATERIAL"IO"
CDS_LMAN_SYM_OUTLINE"-50,225,50,-225"
NEEDS_NO_SIZE"True"
CDS_LIB"pure_quanta"
LOCATION"J7"
$SEC"1"
CDS_SEC"1";
"8"
$PN"8"15;
"7"
$PN"7"4;
"6"
$PN"6"14;
"5"
$PN"5"13;
"4"
$PN"4"12;
"3"
$PN"3"11;
"2"
$PN"2"10;
"1"
$PN"1"9;
%"Q_RES"
"1","(-2425,-100)","0","pure_quanta","I140";
;
VALUE"10K"
MATERIAL"EMPTY"
PART_NUMBER"CS31002FB08"
PACK_TYPE"0402LF"
TOLERANCE"1%"
WATTAGE"1/16W"
CDS_LIB"pure_quanta"
LOCATION"R202"
$SEC"1"
CDS_SEC"1";
"B"
$PN"2"33;
"A"
$PN"1"8;
%"Q_RES"
"1","(-575,4050)","0","pure_quanta","I141";
;
MATERIAL"CHIP"
VALUE"4.7K"
CDS_LIB"pure_quanta"
TOLERANCE"1%"
WATTAGE"1/16W"
PACK_TYPE"0402LF"
PART_NUMBER"CS24702FB06"
$LOCATION"R285"
CDS_LOCATION"R285"
$SEC"1"
CDS_SEC"1";
"B"
$PN"2"6;
"A"
$PN"1"29;
%"UNIVERSAL_GND"
"1","(-125,4050)","1","logical_power","I142";
;
CDS_LIB"logical_power"
HDL_POWER"GND";
"A"6;
%"Q_RES"
"1","(-2400,-200)","0","pure_quanta","I143";
;
MATERIAL"CHIP"
VALUE"10K"
PART_NUMBER"CS31002FB08"
PACK_TYPE"0402LF"
WATTAGE"1/16W"
TOLERANCE"1%"
CDS_LIB"pure_quanta"
LOCATION"R206"
$SEC"1"
CDS_SEC"1";
"B"
$PN"2"25;
"A"
$PN"1"8;
%"SCHOTTKY_12"
"1","(3850,4325)","2","pure_quanta","I144";
;
VALUE"1N5819HW"
MATERIAL"IC"
PART_TYPE"SMLF"
PART_NUMBER"BC005819Z40"
CDS_LIB"pure_quanta"
NEEDS_NO_SIZE"TRUE"
CDS_LMAN_SYM_OUTLINE"-75,50,75,-50"
$LOCATION"D20"
CDS_LOCATION"D20"
$SEC"1"
CDS_SEC"1";
"C"
$PN"2"9;
"A"
$PN"1"2;
%"UNIVERSAL_GND"
"1","(3150,2850)","0","logical_power","I145";
;
HDL_POWER"GND"
CDS_LIB"logical_power";
"A"4;
%"UNIVERSAL_GND"
"1","(3575,3625)","0","logical_power","I19";
;
CDS_LIB"logical_power"
HDL_POWER"GND";
"A"5;
%"UNIVERSAL_POWER"
"1","(4175,4450)","0","logical_power","I20";
;
HDL_POWER"P3V3_AUX"
CDS_LIB"logical_power";
"A"2;
%"Q_CAP"
"1","(3575,4000)","0","pure_quanta","I21";
;
MATERIAL"X7R"
VOLTAGE"25V"
TOLERANCE"10%"
PACK_TYPE"0402"
PART_NUMBER"CH4104K1B00"
VALUE"0.1UF"
CDS_LIB"pure_quanta"
LOCATION"C217"
$SEC"1"
CDS_SEC"1";
"B"
$PN"2"5;
"A"
$PN"1"9;
%"Q_CAP"
"1","(3275,4000)","0","pure_quanta","I22";
;
TOLERANCE"20%"
MATERIAL"X6S"
PART_NUMBER"CH6101MEB01"
PACK_TYPE"C0402"
VALUE"10UF"
VOLTAGE"6.3V"
CDS_LIB"pure_quanta"
LOCATION"C215"
$SEC"1"
CDS_SEC"1";
"B"
$PN"2"5;
"A"
$PN"1"9;
%"Q_RES"
"1","(4250,3375)","0","pure_quanta","I23";
;
MATERIAL"CHIP"
VALUE"33.2"
TOLERANCE"1%"
PART_NUMBER"CS03322FB03"
PACK_TYPE"0402LF"
WATTAGE"1/16W"
CDS_LIB"pure_quanta"
LOCATION"R518"
$SEC"1"
CDS_SEC"1";
"B"
$PN"2"28;
"A"
$PN"1"12;
%"Q_RES"
"1","(-425,1775)","0","pure_quanta","I78";
;
VALUE"33.2"
MATERIAL"CHIP"
TOLERANCE"1%"
PART_NUMBER"CS03322FB03"
PACK_TYPE"0402LF"
WATTAGE"1/16W"
CDS_LIB"pure_quanta"
LOCATION"R223"
$SEC"1"
CDS_SEC"1";
"B"
$PN"2"18;
"A"
$PN"1"36;
%"Q_RES"
"1","(-425,1825)","0","pure_quanta","I80";
;
VALUE"33.2"
MATERIAL"CHIP"
TOLERANCE"1%"
PART_NUMBER"CS03322FB03"
PACK_TYPE"0402LF"
WATTAGE"1/16W"
CDS_LIB"pure_quanta"
LOCATION"R222"
$SEC"1"
CDS_SEC"1";
"B"
$PN"2"26;
"A"
$PN"1"37;
%"Q_RES"
"1","(-425,1875)","0","pure_quanta","I81";
;
MATERIAL"CHIP"
VALUE"33.2"
TOLERANCE"1%"
PART_NUMBER"CS03322FB03"
PACK_TYPE"0402LF"
WATTAGE"1/16W"
CDS_LIB"pure_quanta"
LOCATION"R221"
$SEC"1"
CDS_SEC"1";
"B"
$PN"2"27;
"A"
$PN"1"38;
%"Q_RES"
"1","(-425,1675)","0","pure_quanta","I87";
;
PART_NUMBER"CS03322FB03"
WATTAGE"1/16W"
TOLERANCE"1%"
PACK_TYPE"0402LF"
MATERIAL"CHIP"
VALUE"33.2"
CDS_LIB"pure_quanta"
LOCATION"R224"
$SEC"1"
CDS_SEC"1";
"B"
$PN"2"19;
"A"
$PN"1"34;
%"Q_RES"
"1","(-425,1725)","0","pure_quanta","I88";
;
VALUE"33.2"
MATERIAL"CHIP"
TOLERANCE"1%"
PART_NUMBER"CS03322FB03"
PACK_TYPE"0402LF"
WATTAGE"1/16W"
CDS_LIB"pure_quanta"
LOCATION"R639"
$SEC"1"
CDS_SEC"1";
"B"
$PN"2"17;
"A"
$PN"1"35;
%"Q_RES"
"1","(-700,3375)","0","pure_quanta","I94";
;
VALUE"33.2"
MATERIAL"CHIP"
TOLERANCE"1%"
PART_NUMBER"CS03322FB03"
PACK_TYPE"0402LF"
WATTAGE"1/16W"
CDS_LIB"pure_quanta"
LOCATION"R514"
$SEC"1"
CDS_SEC"1";
"B"
$PN"2"48;
"A"
$PN"1"29;
%"Q_RES"
"1","(-700,3275)","0","pure_quanta","I95";
;
VALUE"33.2"
MATERIAL"CHIP"
TOLERANCE"1%"
PART_NUMBER"CS03322FB03"
PACK_TYPE"0402LF"
WATTAGE"1/16W"
CDS_LIB"pure_quanta"
LOCATION"R516"
$SEC"1"
CDS_SEC"1";
"B"
$PN"2"42;
"A"
$PN"1"39;
%"Q_RES"
"1","(-700,3325)","0","pure_quanta","I96";
;
VALUE"33.2"
MATERIAL"CHIP"
TOLERANCE"1%"
PART_NUMBER"CS03322FB03"
PACK_TYPE"0402LF"
WATTAGE"1/16W"
CDS_LIB"pure_quanta"
LOCATION"R515"
$SEC"1"
CDS_SEC"1";
"B"
$PN"2"47;
"A"
$PN"1"40;
%"Q_RES"
"1","(-700,3225)","0","pure_quanta","I97";
;
MATERIAL"CHIP"
VALUE"33.2"
TOLERANCE"1%"
PART_NUMBER"CS03322FB03"
PACK_TYPE"0402LF"
WATTAGE"1/16W"
CDS_LIB"pure_quanta"
LOCATION"R517"
$SEC"1"
CDS_SEC"1";
"B"
$PN"2"16;
"A"
$PN"1"41;
END.
